# SCM (Grand Teton) — schematic netlist excerpt (pin names and nets, part order shuffled) for the footprints in the layout excerpt that follows; sources: Cadence DE-HDL packaged netlist, KiCad conversion of 12092022_DA0F0TMDCD0_F0T_Management_Board_D_brd_V3_OCP.brd

R835  Q_RES  4.7K 1% CHIP  pkg 0402LF  page 42 : A = P3V3_AUX ; B = FM_ADR_TRIGGER_N
R640  Q_RES  4.7K 1% EMPTY  pkg 0402LF  page 42 : A = P3V3_AUX ; B = FM_JTAG_BMC_MUX_SEL

(kicad_pcb
	(version 20260206)
	(generator "pcbnew")
	(generator_version "10.0")
	(general
		(thickness 1.6)
		(legacy_teardrops no)
	)
	(paper "A4")
	(title_block
		(title "12092022_DA0F0TMDCD0_F0T_Management_Board_D_brd_V3_OCP.brd")
		(comment 1 "Grand Teton / footprints 1131-1132 of 1440")
	)
	(layers
		(0 "F.Cu" signal "TOP")
		(4 "In1.Cu" signal "GND")
		(6 "In2.Cu" signal "IN1")
		(8 "In3.Cu" signal "GND1")
		(10 "In4.Cu" signal "IN2")
		(12 "In5.Cu" signal "VCC")
		(14 "In6.Cu" signal "VCC1")
		(16 "In7.Cu" signal "IN3")
		(18 "In8.Cu" signal "GND2")
		(20 "In9.Cu" signal "IN4")
		(22 "In10.Cu" signal "GND3")
		(2 "B.Cu" signal "BOTTOM")
		(9 "F.Adhes" user "F.Adhesive")
		(11 "B.Adhes" user "B.Adhesive")
		(13 "F.Paste" user "Package Geometry/Pastemask Top")
		(15 "B.Paste" user "Package Geometry/Pastemask Bottom")
		(5 "F.SilkS" user "Ref Des/Silkscreen Top")
		(7 "B.SilkS" user "Ref Des/Silkscreen Bottom")
		(1 "F.Mask" user "Board Geometry/Soldermask Top")
		(3 "B.Mask" user "Board Geometry/Soldermask Bottom")
		(17 "Dwgs.User" user "User.Drawings")
		(19 "Cmts.User" user "User.Comments")
		(21 "Eco1.User" user "User.Eco1")
		(23 "Eco2.User" user "User.Eco2")
		(25 "Edge.Cuts" user "Board Geometry/Outline")
		(27 "Margin" user)
		(31 "F.CrtYd" user "Package Geometry/Place Bound Top")
		(29 "B.CrtYd" user "Package Geometry/Place Bound Bottom")
		(35 "F.Fab" user "Ref Des/Assembly Top")
		(33 "B.Fab" user "Ref Des/Assembly Bottom")
	)
	(footprint ""
		(layer "B.Cu")
		(at 43.434 -67.818)
		(property "Reference" "R640"
			(at 0 0 0)
			(layer "B.SilkS")
			(hide yes)
			(effects
				(font
					(size 1.27 1.27)
				)
				(justify mirror)
			)
		)
		(property "Value" ""
			(at 0 0 0)
			(layer "B.Fab")
			(effects
				(font
					(size 1.27 1.27)
				)
				(justify mirror)
			)
		)
		(duplicate_pad_numbers_are_jumpers no)
		(fp_line
			(start -0.7874 -0.4064)
			(end -0.7874 0.4064)
			(stroke
				(width 0.1524)
				(type default)
			)
			(layer "B.SilkS")
		)
		(fp_line
			(start -0.7874 0.4064)
			(end 0.7874 0.4064)
			(stroke
				(width 0.1524)
				(type default)
			)
			(layer "B.SilkS")
		)
		(fp_line
			(start 0.7874 -0.4064)
			(end -0.7874 -0.4064)
			(stroke
				(width 0.1524)
				(type default)
			)
			(layer "B.SilkS")
		)
		(fp_line
			(start 0.7874 0.4064)
			(end 0.7874 -0.4064)
			(stroke
				(width 0.1524)
				(type default)
			)
			(layer "B.SilkS")
		)
		(fp_line
			(start -0.67945 -0.3048)
			(end -0.67945 0.3048)
			(stroke
				(width 0.1)
				(type default)
			)
			(layer "B.Fab")
		)
		(fp_line
			(start -0.67945 0.3048)
			(end -0.120396 0.3048)
			(stroke
				(width 0.1)
				(type default)
			)
			(layer "B.Fab")
		)
		(fp_line
			(start -0.12065 -0.3048)
			(end -0.67945 -0.3048)
			(stroke
				(width 0.1)
				(type default)
			)
			(layer "B.Fab")
		)
		(fp_line
			(start -0.12065 -0.2794)
			(end -0.12065 -0.3048)
			(stroke
				(width 0.1)
				(type default)
			)
			(layer "B.Fab")
		)
		(fp_line
			(start -0.120396 0.2794)
			(end 0.12065 0.2794)
			(stroke
				(width 0.1)
				(type default)
			)
			(layer "B.Fab")
		)
		(fp_line
			(start -0.120396 0.3048)
			(end -0.120396 0.2794)
			(stroke
				(width 0.1)
				(type default)
			)
			(layer "B.Fab")
		)
		(fp_line
			(start 0.12065 -0.305054)
			(end 0.12065 -0.2794)
			(stroke
				(width 0.1)
				(type default)
			)
			(layer "B.Fab")
		)
		(fp_line
			(start 0.12065 -0.2794)
			(end -0.12065 -0.2794)
			(stroke
				(width 0.1)
				(type default)
			)
			(layer "B.Fab")
		)
		(fp_line
			(start 0.12065 0.2794)
			(end 0.12065 0.3048)
			(stroke
				(width 0.1)
				(type default)
			)
			(layer "B.Fab")
		)
		(fp_line
			(start 0.12065 0.3048)
			(end 0.67945 0.3048)
			(stroke
				(width 0.1)
				(type default)
			)
			(layer "B.Fab")
		)
		(fp_line
			(start 0.67945 -0.305054)
			(end 0.12065 -0.305054)
			(stroke
				(width 0.1)
				(type default)
			)
			(layer "B.Fab")
		)
		(fp_line
			(start 0.67945 0.3048)
			(end 0.67945 -0.305054)
			(stroke
				(width 0.1)
				(type default)
			)
			(layer "B.Fab")
		)
		(pad "1" smd circle
			(at 0.40005 0 180)
			(size 0 0)
			(layers "B.Cu" "B.Mask" "B.Paste")
			(net "P3V3_AUX")
		)
		(pad "2" smd circle
			(at -0.40005 0 180)
			(size 0 0)
			(layers "B.Cu" "B.Mask" "B.Paste")
			(net "FM_JTAG_BMC_MUX_SEL")
		)
	)
	(footprint ""
		(layer "B.Cu")
		(at 14.7828 -95.5802 180)
		(property "Reference" "R835"
			(at 0 0 0)
			(layer "B.SilkS")
			(hide yes)
			(effects
				(font
					(size 1.27 1.27)
				)
				(justify mirror)
			)
		)
		(property "Value" ""
			(at 0 0 0)
			(layer "B.Fab")
			(effects
				(font
					(size 1.27 1.27)
				)
				(justify mirror)
			)
		)
		(duplicate_pad_numbers_are_jumpers no)
		(fp_line
			(start 0.7874 0.4064)
			(end 0.7874 -0.4064)
			(stroke
				(width 0.1524)
				(type default)
			)
			(layer "B.SilkS")
		)
		(fp_line
			(start 0.7874 -0.4064)
			(end -0.7874 -0.4064)
			(stroke
				(width 0.1524)
				(type default)
			)
			(layer "B.SilkS")
		)
		(fp_line
			(start -0.7874 0.4064)
			(end 0.7874 0.4064)
			(stroke
				(width 0.1524)
				(type default)
			)
			(layer "B.SilkS")
		)
		(fp_line
			(start -0.7874 -0.4064)
			(end -0.7874 0.4064)
			(stroke
				(width 0.1524)
				(type default)
			)
			(layer "B.SilkS")
		)
		(fp_line
			(start 0.67945 0.3048)
			(end 0.67945 -0.305054)
			(stroke
				(width 0.1)
				(type default)
			)
			(layer "B.Fab")
		)
		(fp_line
			(start 0.67945 -0.305054)
			(end 0.12065 -0.305054)
			(stroke
				(width 0.1)
				(type default)
			)
			(layer "B.Fab")
		)
		(fp_line
			(start 0.12065 0.3048)
			(end 0.67945 0.3048)
			(stroke
				(width 0.1)
				(type default)
			)
			(layer "B.Fab")
		)
		(fp_line
			(start 0.12065 0.2794)
			(end 0.12065 0.3048)
			(stroke
				(width 0.1)
				(type default)
			)
			(layer "B.Fab")
		)
		(fp_line
			(start 0.12065 -0.2794)
			(end -0.12065 -0.2794)
			(stroke
				(width 0.1)
				(type default)
			)
			(layer "B.Fab")
		)
		(fp_line
			(start 0.12065 -0.305054)
			(end 0.12065 -0.2794)
			(stroke
				(width 0.1)
				(type default)
			)
			(layer "B.Fab")
		)
		(fp_line
			(start -0.120396 0.3048)
			(end -0.120396 0.2794)
			(stroke
				(width 0.1)
				(type default)
			)
			(layer "B.Fab")
		)
		(fp_line
			(start -0.120396 0.2794)
			(end 0.12065 0.2794)
			(stroke
				(width 0.1)
				(type default)
			)
			(layer "B.Fab")
		)
		(fp_line
			(start -0.12065 -0.2794)
			(end -0.12065 -0.3048)
			(stroke
				(width 0.1)
				(type default)
			)
			(layer "B.Fab")
		)
		(fp_line
			(start -0.12065 -0.3048)
			(end -0.67945 -0.3048)
			(stroke
				(width 0.1)
				(type default)
			)
			(layer "B.Fab")
		)
		(fp_line
			(start -0.67945 0.3048)
			(end -0.120396 0.3048)
			(stroke
				(width 0.1)
				(type default)
			)
			(layer "B.Fab")
		)
		(fp_line
			(start -0.67945 -0.3048)
			(end -0.67945 0.3048)
			(stroke
				(width 0.1)
				(type default)
			)
			(layer "B.Fab")
		)
		(pad "1" smd circle
			(at 0.40005 0)
			(size 0 0)
			(layers "B.Cu" "B.Mask" "B.Paste")
			(net "P3V3_AUX")
		)
		(pad "2" smd circle
			(at -0.40005 0)
			(size 0 0)
			(layers "B.Cu" "B.Mask" "B.Paste")
			(net "FM_ADR_TRIGGER_N")
		)
	)
)
